# SCM (Grand Teton) — schematic netlist excerpt (pin names and nets, part order shuffled) for the footprints in the layout excerpt that follows; sources: Cadence DE-HDL packaged netlist, KiCad conversion of 12092022_DA0F0TMDCD0_F0T_Management_Board_D_brd_V3_OCP.brd

R602  Q_RES  750 1% CHIP  pkg 0402LF  page 47 : A = LED_POSTCODE_2 ; B = LED_POSTCODE_2_R
R815  Q_RES  10K 1% CHIP  pkg 0402LF  page 49 : A = P5V_AUX ; B = HDD_LED_BUF_R

(kicad_pcb
	(version 20260206)
	(generator "pcbnew")
	(generator_version "10.0")
	(general
		(thickness 1.6)
		(legacy_teardrops no)
	)
	(paper "A4")
	(title_block
		(title "12092022_DA0F0TMDCD0_F0T_Management_Board_D_brd_V3_OCP.brd")
		(comment 1 "Grand Teton / footprints 620-621 of 1440")
	)
	(layers
		(0 "F.Cu" signal "TOP")
		(4 "In1.Cu" signal "GND")
		(6 "In2.Cu" signal "IN1")
		(8 "In3.Cu" signal "GND1")
		(10 "In4.Cu" signal "IN2")
		(12 "In5.Cu" signal "VCC")
		(14 "In6.Cu" signal "VCC1")
		(16 "In7.Cu" signal "IN3")
		(18 "In8.Cu" signal "GND2")
		(20 "In9.Cu" signal "IN4")
		(22 "In10.Cu" signal "GND3")
		(2 "B.Cu" signal "BOTTOM")
		(9 "F.Adhes" user "F.Adhesive")
		(11 "B.Adhes" user "B.Adhesive")
		(13 "F.Paste" user "Package Geometry/Pastemask Top")
		(15 "B.Paste" user "Package Geometry/Pastemask Bottom")
		(5 "F.SilkS" user "Ref Des/Silkscreen Top")
		(7 "B.SilkS" user "Ref Des/Silkscreen Bottom")
		(1 "F.Mask" user "Board Geometry/Soldermask Top")
		(3 "B.Mask" user "Board Geometry/Soldermask Bottom")
		(17 "Dwgs.User" user "User.Drawings")
		(19 "Cmts.User" user "User.Comments")
		(21 "Eco1.User" user "User.Eco1")
		(23 "Eco2.User" user "User.Eco2")
		(25 "Edge.Cuts" user "Board Geometry/Outline")
		(27 "Margin" user)
		(31 "F.CrtYd" user "Package Geometry/Place Bound Top")
		(29 "B.CrtYd" user "Package Geometry/Place Bound Bottom")
		(35 "F.Fab" user "Ref Des/Assembly Top")
		(33 "B.Fab" user "Ref Des/Assembly Bottom")
	)
	(footprint ""
		(layer "F.Cu")
		(at 72.46493 -28.546044 90)
		(property "Reference" "R602"
			(at 0 0 90)
			(layer "F.SilkS")
			(hide yes)
			(effects
				(font
					(size 1.27 1.27)
				)
			)
		)
		(property "Value" ""
			(at 0 0 90)
			(layer "F.Fab")
			(effects
				(font
					(size 1.27 1.27)
				)
			)
		)
		(duplicate_pad_numbers_are_jumpers no)
		(fp_line
			(start 0.7874 -0.4064)
			(end 0.7874 0.4064)
			(stroke
				(width 0.1524)
				(type default)
			)
			(layer "F.SilkS")
		)
		(fp_line
			(start -0.7874 -0.4064)
			(end 0.7874 -0.4064)
			(stroke
				(width 0.1524)
				(type default)
			)
			(layer "F.SilkS")
		)
		(fp_line
			(start 0.7874 0.4064)
			(end -0.7874 0.4064)
			(stroke
				(width 0.1524)
				(type default)
			)
			(layer "F.SilkS")
		)
		(fp_line
			(start -0.7874 0.4064)
			(end -0.7874 -0.4064)
			(stroke
				(width 0.1524)
				(type default)
			)
			(layer "F.SilkS")
		)
		(fp_line
			(start -0.12065 -0.305054)
			(end -0.12065 -0.2794)
			(stroke
				(width 0.1)
				(type default)
			)
			(layer "F.Fab")
		)
		(fp_line
			(start -0.67945 -0.305054)
			(end -0.12065 -0.305054)
			(stroke
				(width 0.1)
				(type default)
			)
			(layer "F.Fab")
		)
		(fp_line
			(start 0.67945 -0.3048)
			(end 0.67945 0.3048)
			(stroke
				(width 0.1)
				(type default)
			)
			(layer "F.Fab")
		)
		(fp_line
			(start 0.12065 -0.3048)
			(end 0.67945 -0.3048)
			(stroke
				(width 0.1)
				(type default)
			)
			(layer "F.Fab")
		)
		(fp_line
			(start 0.12065 -0.2794)
			(end 0.12065 -0.3048)
			(stroke
				(width 0.1)
				(type default)
			)
			(layer "F.Fab")
		)
		(fp_line
			(start -0.12065 -0.2794)
			(end 0.12065 -0.2794)
			(stroke
				(width 0.1)
				(type default)
			)
			(layer "F.Fab")
		)
		(fp_line
			(start 0.120396 0.2794)
			(end -0.12065 0.2794)
			(stroke
				(width 0.1)
				(type default)
			)
			(layer "F.Fab")
		)
		(fp_line
			(start -0.12065 0.2794)
			(end -0.12065 0.3048)
			(stroke
				(width 0.1)
				(type default)
			)
			(layer "F.Fab")
		)
		(fp_line
			(start 0.67945 0.3048)
			(end 0.120396 0.3048)
			(stroke
				(width 0.1)
				(type default)
			)
			(layer "F.Fab")
		)
		(fp_line
			(start 0.120396 0.3048)
			(end 0.120396 0.2794)
			(stroke
				(width 0.1)
				(type default)
			)
			(layer "F.Fab")
		)
		(fp_line
			(start -0.12065 0.3048)
			(end -0.67945 0.3048)
			(stroke
				(width 0.1)
				(type default)
			)
			(layer "F.Fab")
		)
		(fp_line
			(start -0.67945 0.3048)
			(end -0.67945 -0.305054)
			(stroke
				(width 0.1)
				(type default)
			)
			(layer "F.Fab")
		)
		(pad "1" smd circle
			(at -0.40005 0 90)
			(size 0 0)
			(layers "F.Cu" "F.Mask" "F.Paste")
			(net "LED_POSTCODE_2")
		)
		(pad "2" smd circle
			(at 0.40005 0 90)
			(size 0 0)
			(layers "F.Cu" "F.Mask" "F.Paste")
			(net "LED_POSTCODE_2_R")
		)
	)
	(footprint ""
		(layer "F.Cu")
		(at 29.591 -10.287 -90)
		(property "Reference" "R815"
			(at 0 0 270)
			(layer "F.SilkS")
			(hide yes)
			(effects
				(font
					(size 1.27 1.27)
				)
			)
		)
		(property "Value" ""
			(at 0 0 270)
			(layer "F.Fab")
			(effects
				(font
					(size 1.27 1.27)
				)
			)
		)
		(duplicate_pad_numbers_are_jumpers no)
		(fp_line
			(start -0.7874 0.4064)
			(end -0.7874 -0.4064)
			(stroke
				(width 0.1524)
				(type default)
			)
			(layer "F.SilkS")
		)
		(fp_line
			(start 0.7874 0.4064)
			(end -0.7874 0.4064)
			(stroke
				(width 0.1524)
				(type default)
			)
			(layer "F.SilkS")
		)
		(fp_line
			(start -0.7874 -0.4064)
			(end 0.7874 -0.4064)
			(stroke
				(width 0.1524)
				(type default)
			)
			(layer "F.SilkS")
		)
		(fp_line
			(start 0.7874 -0.4064)
			(end 0.7874 0.4064)
			(stroke
				(width 0.1524)
				(type default)
			)
			(layer "F.SilkS")
		)
		(fp_line
			(start -0.67945 0.3048)
			(end -0.67945 -0.305054)
			(stroke
				(width 0.1)
				(type default)
			)
			(layer "F.Fab")
		)
		(fp_line
			(start -0.12065 0.3048)
			(end -0.67945 0.3048)
			(stroke
				(width 0.1)
				(type default)
			)
			(layer "F.Fab")
		)
		(fp_line
			(start 0.120396 0.3048)
			(end 0.120396 0.2794)
			(stroke
				(width 0.1)
				(type default)
			)
			(layer "F.Fab")
		)
		(fp_line
			(start 0.67945 0.3048)
			(end 0.120396 0.3048)
			(stroke
				(width 0.1)
				(type default)
			)
			(layer "F.Fab")
		)
		(fp_line
			(start -0.12065 0.2794)
			(end -0.12065 0.3048)
			(stroke
				(width 0.1)
				(type default)
			)
			(layer "F.Fab")
		)
		(fp_line
			(start 0.120396 0.2794)
			(end -0.12065 0.2794)
			(stroke
				(width 0.1)
				(type default)
			)
			(layer "F.Fab")
		)
		(fp_line
			(start -0.12065 -0.2794)
			(end 0.12065 -0.2794)
			(stroke
				(width 0.1)
				(type default)
			)
			(layer "F.Fab")
		)
		(fp_line
			(start 0.12065 -0.2794)
			(end 0.12065 -0.3048)
			(stroke
				(width 0.1)
				(type default)
			)
			(layer "F.Fab")
		)
		(fp_line
			(start 0.12065 -0.3048)
			(end 0.67945 -0.3048)
			(stroke
				(width 0.1)
				(type default)
			)
			(layer "F.Fab")
		)
		(fp_line
			(start 0.67945 -0.3048)
			(end 0.67945 0.3048)
			(stroke
				(width 0.1)
				(type default)
			)
			(layer "F.Fab")
		)
		(fp_line
			(start -0.67945 -0.305054)
			(end -0.12065 -0.305054)
			(stroke
				(width 0.1)
				(type default)
			)
			(layer "F.Fab")
		)
		(fp_line
			(start -0.12065 -0.305054)
			(end -0.12065 -0.2794)
			(stroke
				(width 0.1)
				(type default)
			)
			(layer "F.Fab")
		)
		(pad "1" smd circle
			(at -0.40005 0 270)
			(size 0 0)
			(layers "F.Cu" "F.Mask" "F.Paste")
			(net "P5V_AUX")
		)
		(pad "2" smd circle
			(at 0.40005 0 270)
			(size 0 0)
			(layers "F.Cu" "F.Mask" "F.Paste")
			(net "HDD_LED_BUF_R")
		)
	)
)
